(kicad_pcb
	(version 20260206)
	(generator "pcbnew")
	(generator_version "10.0")
	(general
		(thickness 1.6)
		(legacy_teardrops no)
	)
	(paper "A4")
	(title_block
		(title "baseboard — 13948-1b.1110WZS1818.brd")
		(comment 1 "Honey Badger (Wiwynn) / footprints 1800-1807 of 2523")
	)
	(layers
		(0 "F.Cu" signal "TOP")
		(4 "In1.Cu" signal "L2GND")
		(6 "In2.Cu" signal "L3")
		(8 "In3.Cu" signal "L4VCC")
		(10 "In4.Cu" signal "L5VCC")
		(12 "In5.Cu" signal "L6")
		(14 "In6.Cu" signal "L7GND")
		(2 "B.Cu" signal "BOTTOM")
		(9 "F.Adhes" user "F.Adhesive")
		(11 "B.Adhes" user "B.Adhesive")
		(13 "F.Paste" user "Package Geometry/Pastemask Top")
		(15 "B.Paste" user "Package Geometry/Pastemask Bottom")
		(5 "F.SilkS" user "Ref Des/Silkscreen Top")
		(7 "B.SilkS" user "Ref Des/Silkscreen Bottom")
		(1 "F.Mask" user "Board Geometry/Soldermask Top")
		(3 "B.Mask" user "Board Geometry/Soldermask Bottom")
		(17 "Dwgs.User" user "User.Drawings")
		(19 "Cmts.User" user "User.Comments")
		(21 "Eco1.User" user "User.Eco1")
		(23 "Eco2.User" user "User.Eco2")
		(25 "Edge.Cuts" user "Board Geometry/Outline")
		(27 "Margin" user)
		(31 "F.CrtYd" user "Package Geometry/Place Bound Top")
		(29 "B.CrtYd" user "Package Geometry/Place Bound Bottom")
		(35 "F.Fab" user "Ref Des/Assembly Top")
		(33 "B.Fab" user "Ref Des/Assembly Bottom")
	)
	(footprint ""
		(layer "B.Cu")
		(at 115.767612 -221.996 180)
		(property "Reference" "SC1292"
			(at 0 0 0)
			(layer "B.SilkS")
			(hide yes)
			(effects
				(font
					(size 1.27 1.27)
				)
				(justify mirror)
			)
		)
		(property "Value" "SCD1U16V2KX-3GP"
			(at -1.1811 -2.7051 180)
			(unlocked yes)
			(layer "B.Fab")
			(hide yes)
			(effects
				(font
					(size 1.016 1.016)
					(thickness 0.1524)
				)
				(justify mirror)
			)
		)
		(property "Device Type" "C402H22"
			(at -1.1811 -4.2291 180)
			(unlocked yes)
			(layer "B.Fab")
			(hide yes)
			(effects
				(font
					(size 1.016 1.016)
					(thickness 0.1524)
				)
				(justify mirror)
			)
		)
		(duplicate_pad_numbers_are_jumpers no)
		(fp_rect
			(start 0.4318 0.9525)
			(end -0.4318 -0.9525)
			(stroke
				(width 0)
				(type default)
			)
			(fill no)
			(layer "B.CrtYd")
		)
		(fp_rect
			(start 0.4318 0.9525)
			(end -0.4318 -0.9525)
			(stroke
				(width 0)
				(type default)
			)
			(fill no)
			(layer "B.Fab")
		)
		(pad "1" smd custom
			(at 0 -0.4445)
			(size 0.1524 0.1524)
			(layers "B.Cu" "B.Mask" "B.Paste")
			(net "1.2V_REDV")
			(options
				(clearance outline)
				(anchor circle)
			)
			(primitives
				(gr_poly
					(pts
						(arc
							(start 0.3048 0.2032)
							(mid 0.275042 0.275042)
							(end 0.2032 0.3048)
						)
						(arc
							(start -0.2032 0.3048)
							(mid -0.275042 0.275042)
							(end -0.3048 0.2032)
						)
						(arc
							(start -0.3048 -0.2032)
							(mid -0.275042 -0.275042)
							(end -0.2032 -0.3048)
						)
						(arc
							(start 0.2032 -0.3048)
							(mid 0.275042 -0.275042)
							(end 0.3048 -0.2032)
						)
					)
					(width 0)
					(fill yes)
				)
			)
		)
		(pad "2" smd custom
			(at 0 0.4445)
			(size 0.1524 0.1524)
			(layers "B.Cu" "B.Mask" "B.Paste")
			(net "GND")
			(options
				(clearance outline)
				(anchor circle)
			)
			(primitives
				(gr_poly
					(pts
						(arc
							(start 0.3048 0.2032)
							(mid 0.275042 0.275042)
							(end 0.2032 0.3048)
						)
						(arc
							(start -0.2032 0.3048)
							(mid -0.275042 0.275042)
							(end -0.3048 0.2032)
						)
						(arc
							(start -0.3048 -0.2032)
							(mid -0.275042 -0.275042)
							(end -0.2032 -0.3048)
						)
						(arc
							(start 0.2032 -0.3048)
							(mid 0.275042 -0.275042)
							(end 0.3048 -0.2032)
						)
					)
					(width 0)
					(fill yes)
				)
			)
		)
	)
	(footprint ""
		(layer "B.Cu")
		(at 290.186872 -174.824136 90)
		(property "Reference" "C212"
			(at 0 0 90)
			(layer "B.SilkS")
			(hide yes)
			(effects
				(font
					(size 1.27 1.27)
				)
				(justify mirror)
			)
		)
		(property "Value" "SC1U10V2KX-1GP"
			(at -1.1811 -2.7051 90)
			(unlocked yes)
			(layer "B.Fab")
			(hide yes)
			(effects
				(font
					(size 1.016 1.016)
					(thickness 0.1524)
				)
				(justify mirror)
			)
		)
		(property "Device Type" "C402H22"
			(at -1.1811 -4.2291 90)
			(unlocked yes)
			(layer "B.Fab")
			(hide yes)
			(effects
				(font
					(size 1.016 1.016)
					(thickness 0.1524)
				)
				(justify mirror)
			)
		)
		(duplicate_pad_numbers_are_jumpers no)
		(fp_rect
			(start 0.4318 0.9525)
			(end -0.4318 -0.9525)
			(stroke
				(width 0)
				(type default)
			)
			(fill no)
			(layer "B.CrtYd")
		)
		(fp_rect
			(start 0.4318 0.9525)
			(end -0.4318 -0.9525)
			(stroke
				(width 0)
				(type default)
			)
			(fill no)
			(layer "B.Fab")
		)
		(pad "1" smd custom
			(at 0 -0.4445 270)
			(size 0.1524 0.1524)
			(layers "B.Cu" "B.Mask" "B.Paste")
			(net "P1V26_STBY")
			(options
				(clearance outline)
				(anchor circle)
			)
			(primitives
				(gr_poly
					(pts
						(arc
							(start 0.3048 0.2032)
							(mid 0.275042 0.275042)
							(end 0.2032 0.3048)
						)
						(arc
							(start -0.2032 0.3048)
							(mid -0.275042 0.275042)
							(end -0.3048 0.2032)
						)
						(arc
							(start -0.3048 -0.2032)
							(mid -0.275042 -0.275042)
							(end -0.2032 -0.3048)
						)
						(arc
							(start 0.2032 -0.3048)
							(mid 0.275042 -0.275042)
							(end 0.3048 -0.2032)
						)
					)
					(width 0)
					(fill yes)
				)
			)
		)
		(pad "2" smd custom
			(at 0 0.4445 270)
			(size 0.1524 0.1524)
			(layers "B.Cu" "B.Mask" "B.Paste")
			(net "GND")
			(options
				(clearance outline)
				(anchor circle)
			)
			(primitives
				(gr_poly
					(pts
						(arc
							(start 0.3048 0.2032)
							(mid 0.275042 0.275042)
							(end 0.2032 0.3048)
						)
						(arc
							(start -0.2032 0.3048)
							(mid -0.275042 0.275042)
							(end -0.3048 0.2032)
						)
						(arc
							(start -0.3048 -0.2032)
							(mid -0.275042 -0.275042)
							(end -0.2032 -0.3048)
						)
						(arc
							(start 0.2032 -0.3048)
							(mid 0.275042 -0.275042)
							(end 0.3048 -0.2032)
						)
					)
					(width 0)
					(fill yes)
				)
			)
		)
	)
	(footprint ""
		(layer "B.Cu")
		(at 117.545612 -204.978 180)
		(property "Reference" "SR888"
			(at 0 0 0)
			(layer "B.SilkS")
			(hide yes)
			(effects
				(font
					(size 1.27 1.27)
				)
				(justify mirror)
			)
		)
		(property "Value" "0R2J-2-GP"
			(at -0.064008 -3.993896 180)
			(unlocked yes)
			(layer "B.Fab")
			(hide yes)
			(effects
				(font
					(size 1.016 1.016)
					(thickness 0.1524)
				)
				(justify mirror)
			)
		)
		(property "Device Type" "R402H16"
			(at -0.064008 -5.517896 180)
			(unlocked yes)
			(layer "B.Fab")
			(hide yes)
			(effects
				(font
					(size 1.016 1.016)
					(thickness 0.1524)
				)
				(justify mirror)
			)
		)
		(duplicate_pad_numbers_are_jumpers no)
		(fp_line
			(start 0.508 -0.9398)
			(end 0.508 0.9398)
			(stroke
				(width 0.1524)
				(type default)
			)
			(layer "B.SilkS")
		)
		(fp_line
			(start -0.508 -0.9398)
			(end 0.508 -0.9398)
			(stroke
				(width 0.1524)
				(type default)
			)
			(layer "B.SilkS")
		)
		(fp_rect
			(start 0.508 0.9398)
			(end -0.508 -0.9398)
			(stroke
				(width 0)
				(type default)
			)
			(fill no)
			(layer "B.CrtYd")
		)
		(fp_rect
			(start 0.508 0.9398)
			(end -0.508 -0.9398)
			(stroke
				(width 0)
				(type default)
			)
			(fill no)
			(layer "B.Fab")
		)
		(pad "1" smd custom
			(at 0 -0.4445)
			(size 0.1397 0.1397)
			(layers "B.Cu" "B.Mask" "B.Paste")
			(net "REDV_RX7_P")
			(options
				(clearance outline)
				(anchor circle)
			)
			(primitives
				(gr_poly
					(pts
						(arc
							(start -0.1778 0.2794)
							(mid -0.249642 0.249642)
							(end -0.2794 0.1778)
						)
						(arc
							(start -0.2794 -0.1778)
							(mid -0.249642 -0.249642)
							(end -0.1778 -0.2794)
						)
						(arc
							(start 0.1778 -0.2794)
							(mid 0.249642 -0.249642)
							(end 0.2794 -0.1778)
						)
						(arc
							(start 0.2794 0.1778)
							(mid 0.249642 0.249642)
							(end 0.1778 0.2794)
						)
					)
					(width 0)
					(fill yes)
				)
			)
		)
		(pad "2" smd custom
			(at 0 0.4445)
			(size 0.1397 0.1397)
			(layers "B.Cu" "B.Mask" "B.Paste")
			(net "SAS_HDD_CONN_RX7_P")
			(options
				(clearance outline)
				(anchor circle)
			)
			(primitives
				(gr_poly
					(pts
						(arc
							(start -0.1778 0.2794)
							(mid -0.249642 0.249642)
							(end -0.2794 0.1778)
						)
						(arc
							(start -0.2794 -0.1778)
							(mid -0.249642 -0.249642)
							(end -0.1778 -0.2794)
						)
						(arc
							(start 0.1778 -0.2794)
							(mid 0.249642 -0.249642)
							(end 0.2794 -0.1778)
						)
						(arc
							(start 0.2794 0.1778)
							(mid 0.249642 0.249642)
							(end 0.1778 0.2794)
						)
					)
					(width 0)
					(fill yes)
				)
			)
		)
	)
	(footprint ""
		(layer "B.Cu")
		(at 309.118 -160.655 180)
		(property "Reference" "R261"
			(at 0 0 0)
			(layer "B.SilkS")
			(hide yes)
			(effects
				(font
					(size 1.27 1.27)
				)
				(justify mirror)
			)
		)
		(property "Value" "10KR2F-2-GP"
			(at -0.064008 -3.993896 180)
			(unlocked yes)
			(layer "B.Fab")
			(hide yes)
			(effects
				(font
					(size 1.016 1.016)
					(thickness 0.1524)
				)
				(justify mirror)
			)
		)
		(property "Device Type" "R402H16"
			(at -0.064008 -5.517896 180)
			(unlocked yes)
			(layer "B.Fab")
			(hide yes)
			(effects
				(font
					(size 1.016 1.016)
					(thickness 0.1524)
				)
				(justify mirror)
			)
		)
		(duplicate_pad_numbers_are_jumpers no)
		(fp_line
			(start 0.508 -0.9398)
			(end 0.508 0.9398)
			(stroke
				(width 0.1524)
				(type default)
			)
			(layer "B.SilkS")
		)
		(fp_line
			(start -0.508 -0.9398)
			(end 0.508 -0.9398)
			(stroke
				(width 0.1524)
				(type default)
			)
			(layer "B.SilkS")
		)
		(fp_rect
			(start 0.508 0.9398)
			(end -0.508 -0.9398)
			(stroke
				(width 0)
				(type default)
			)
			(fill no)
			(layer "B.CrtYd")
		)
		(fp_rect
			(start 0.508 0.9398)
			(end -0.508 -0.9398)
			(stroke
				(width 0)
				(type default)
			)
			(fill no)
			(layer "B.Fab")
		)
		(pad "1" smd custom
			(at 0 -0.4445)
			(size 0.1397 0.1397)
			(layers "B.Cu" "B.Mask" "B.Paste")
			(net "P3V3_STBY")
			(options
				(clearance outline)
				(anchor circle)
			)
			(primitives
				(gr_poly
					(pts
						(arc
							(start -0.1778 0.2794)
							(mid -0.249642 0.249642)
							(end -0.2794 0.1778)
						)
						(arc
							(start -0.2794 -0.1778)
							(mid -0.249642 -0.249642)
							(end -0.1778 -0.2794)
						)
						(arc
							(start 0.1778 -0.2794)
							(mid 0.249642 -0.249642)
							(end 0.2794 -0.1778)
						)
						(arc
							(start 0.2794 0.1778)
							(mid 0.249642 0.249642)
							(end 0.1778 0.2794)
						)
					)
					(width 0)
					(fill yes)
				)
			)
		)
		(pad "2" smd custom
			(at 0 0.4445)
			(size 0.1397 0.1397)
			(layers "B.Cu" "B.Mask" "B.Paste")
			(net "PU_BMC0_SDA11")
			(options
				(clearance outline)
				(anchor circle)
			)
			(primitives
				(gr_poly
					(pts
						(arc
							(start -0.1778 0.2794)
							(mid -0.249642 0.249642)
							(end -0.2794 0.1778)
						)
						(arc
							(start -0.2794 -0.1778)
							(mid -0.249642 -0.249642)
							(end -0.1778 -0.2794)
						)
						(arc
							(start 0.1778 -0.2794)
							(mid 0.249642 -0.249642)
							(end 0.2794 -0.1778)
						)
						(arc
							(start 0.2794 0.1778)
							(mid 0.249642 0.249642)
							(end 0.1778 0.2794)
						)
					)
					(width 0)
					(fill yes)
				)
			)
		)
	)
	(footprint ""
		(layer "B.Cu")
		(at 111.31677 -94.488 90)
		(property "Reference" "SC1259"
			(at 0 0 90)
			(layer "B.SilkS")
			(hide yes)
			(effects
				(font
					(size 1.27 1.27)
				)
				(justify mirror)
			)
		)
		(property "Value" "SCD1U6D3V1KX-GP"
			(at 2.8321 -1.7399 90)
			(unlocked yes)
			(layer "B.Fab")
			(hide yes)
			(effects
				(font
					(size 1.016 1.016)
					(thickness 0.1524)
				)
				(justify mirror)
			)
		)
		(property "Device Type" "C0201H13"
			(at 2.8321 -3.2639 90)
			(unlocked yes)
			(layer "B.Fab")
			(hide yes)
			(effects
				(font
					(size 1.016 1.016)
					(thickness 0.1524)
				)
				(justify mirror)
			)
		)
		(duplicate_pad_numbers_are_jumpers no)
		(fp_rect
			(start 0.2794 0.6477)
			(end -0.2794 -0.6477)
			(stroke
				(width 0)
				(type default)
			)
			(fill no)
			(layer "B.CrtYd")
		)
		(fp_rect
			(start 0.2794 0.6477)
			(end -0.2794 -0.6477)
			(stroke
				(width 0)
				(type default)
			)
			(fill no)
			(layer "B.Fab")
		)
		(pad "1" smd custom
			(at 0 -0.2794 270)
			(size 0.0762 0.0762)
			(layers "B.Cu" "B.Mask" "B.Paste")
			(net "P0V9_E")
			(options
				(clearance outline)
				(anchor circle)
			)
			(primitives
				(gr_poly
					(pts
						(arc
							(start 0.1524 0.127)
							(mid 0.137521 0.162921)
							(end 0.1016 0.1778)
						)
						(arc
							(start -0.1016 0.1778)
							(mid -0.137521 0.162921)
							(end -0.1524 0.127)
						)
						(arc
							(start -0.1524 -0.127)
							(mid -0.137521 -0.162921)
							(end -0.1016 -0.1778)
						)
						(arc
							(start 0.1016 -0.1778)
							(mid 0.137521 -0.162921)
							(end 0.1524 -0.127)
						)
					)
					(width 0)
					(fill yes)
				)
			)
		)
		(pad "2" smd custom
			(at 0 0.2794 270)
			(size 0.0762 0.0762)
			(layers "B.Cu" "B.Mask" "B.Paste")
			(net "GND")
			(options
				(clearance outline)
				(anchor circle)
			)
			(primitives
				(gr_poly
					(pts
						(arc
							(start 0.1524 0.127)
							(mid 0.137521 0.162921)
							(end 0.1016 0.1778)
						)
						(arc
							(start -0.1016 0.1778)
							(mid -0.137521 0.162921)
							(end -0.1524 0.127)
						)
						(arc
							(start -0.1524 -0.127)
							(mid -0.137521 -0.162921)
							(end -0.1016 -0.1778)
						)
						(arc
							(start 0.1016 -0.1778)
							(mid 0.137521 -0.162921)
							(end 0.1524 -0.127)
						)
					)
					(width 0)
					(fill yes)
				)
			)
		)
	)
	(footprint ""
		(layer "B.Cu")
		(at 11.169904 -100.400866)
		(property "Reference" "C129"
			(at 0 0 0)
			(layer "B.SilkS")
			(hide yes)
			(effects
				(font
					(size 1.27 1.27)
				)
				(justify mirror)
			)
		)
		(property "Value" "SCD01U50V2KX-1GP"
			(at -1.1811 -2.7051 0)
			(unlocked yes)
			(layer "B.Fab")
			(hide yes)
			(effects
				(font
					(size 1.016 1.016)
					(thickness 0.1524)
				)
				(justify mirror)
			)
		)
		(property "Device Type" "C402H22"
			(at -1.1811 -4.2291 0)
			(unlocked yes)
			(layer "B.Fab")
			(hide yes)
			(effects
				(font
					(size 1.016 1.016)
					(thickness 0.1524)
				)
				(justify mirror)
			)
		)
		(duplicate_pad_numbers_are_jumpers no)
		(fp_rect
			(start 0.4318 0.9525)
			(end -0.4318 -0.9525)
			(stroke
				(width 0)
				(type default)
			)
			(fill no)
			(layer "B.CrtYd")
		)
		(fp_rect
			(start 0.4318 0.9525)
			(end -0.4318 -0.9525)
			(stroke
				(width 0)
				(type default)
			)
			(fill no)
			(layer "B.Fab")
		)
		(pad "1" smd custom
			(at 0 -0.4445 180)
			(size 0.1524 0.1524)
			(layers "B.Cu" "B.Mask" "B.Paste")
			(net "IOC_SAS_RX_P4")
			(options
				(clearance outline)
				(anchor circle)
			)
			(primitives
				(gr_poly
					(pts
						(arc
							(start 0.3048 0.2032)
							(mid 0.275042 0.275042)
							(end 0.2032 0.3048)
						)
						(arc
							(start -0.2032 0.3048)
							(mid -0.275042 0.275042)
							(end -0.3048 0.2032)
						)
						(arc
							(start -0.3048 -0.2032)
							(mid -0.275042 -0.275042)
							(end -0.2032 -0.3048)
						)
						(arc
							(start 0.2032 -0.3048)
							(mid 0.275042 -0.275042)
							(end 0.3048 -0.2032)
						)
					)
					(width 0)
					(fill yes)
				)
			)
		)
		(pad "2" smd custom
			(at 0 0.4445 180)
			(size 0.1524 0.1524)
			(layers "B.Cu" "B.Mask" "B.Paste")
			(net "SAS_EXT_CONN_RX16_P")
			(options
				(clearance outline)
				(anchor circle)
			)
			(primitives
				(gr_poly
					(pts
						(arc
							(start 0.3048 0.2032)
							(mid 0.275042 0.275042)
							(end 0.2032 0.3048)
						)
						(arc
							(start -0.2032 0.3048)
							(mid -0.275042 0.275042)
							(end -0.3048 0.2032)
						)
						(arc
							(start -0.3048 -0.2032)
							(mid -0.275042 -0.275042)
							(end -0.2032 -0.3048)
						)
						(arc
							(start 0.2032 -0.3048)
							(mid 0.275042 -0.275042)
							(end 0.3048 -0.2032)
						)
					)
					(width 0)
					(fill yes)
				)
			)
		)
	)
	(footprint ""
		(layer "B.Cu")
		(at 102.997 -229.997 -90)
		(property "Reference" "R594"
			(at 0 0 90)
			(layer "B.SilkS")
			(hide yes)
			(effects
				(font
					(size 1.27 1.27)
				)
				(justify mirror)
			)
		)
		(property "Value" "0R2J-2-GP"
			(at -0.064008 -3.993896 270)
			(unlocked yes)
			(layer "B.Fab")
			(hide yes)
			(effects
				(font
					(size 1.016 1.016)
					(thickness 0.1524)
				)
				(justify mirror)
			)
		)
		(property "Device Type" "R402H16"
			(at -0.064008 -5.517896 270)
			(unlocked yes)
			(layer "B.Fab")
			(hide yes)
			(effects
				(font
					(size 1.016 1.016)
					(thickness 0.1524)
				)
				(justify mirror)
			)
		)
		(duplicate_pad_numbers_are_jumpers no)
		(fp_line
			(start -0.508 -0.9398)
			(end 0.508 -0.9398)
			(stroke
				(width 0.1524)
				(type default)
			)
			(layer "B.SilkS")
		)
		(fp_line
			(start 0.508 -0.9398)
			(end 0.508 0.9398)
			(stroke
				(width 0.1524)
				(type default)
			)
			(layer "B.SilkS")
		)
		(fp_rect
			(start 0.508 0.9398)
			(end -0.508 -0.9398)
			(stroke
				(width 0)
				(type default)
			)
			(fill no)
			(layer "B.CrtYd")
		)
		(fp_rect
			(start 0.508 0.9398)
			(end -0.508 -0.9398)
			(stroke
				(width 0)
				(type default)
			)
			(fill no)
			(layer "B.Fab")
		)
		(pad "1" smd custom
			(at 0 -0.4445 90)
			(size 0.1397 0.1397)
			(layers "B.Cu" "B.Mask" "B.Paste")
			(net "SAS_FAULT_LED4")
			(options
				(clearance outline)
				(anchor circle)
			)
			(primitives
				(gr_poly
					(pts
						(arc
							(start -0.1778 0.2794)
							(mid -0.249642 0.249642)
							(end -0.2794 0.1778)
						)
						(arc
							(start -0.2794 -0.1778)
							(mid -0.249642 -0.249642)
							(end -0.1778 -0.2794)
						)
						(arc
							(start 0.1778 -0.2794)
							(mid 0.249642 -0.249642)
							(end 0.2794 -0.1778)
						)
						(arc
							(start 0.2794 0.1778)
							(mid 0.249642 0.249642)
							(end 0.1778 0.2794)
						)
					)
					(width 0)
					(fill yes)
				)
			)
		)
		(pad "2" smd custom
			(at 0 0.4445 90)
			(size 0.1397 0.1397)
			(layers "B.Cu" "B.Mask" "B.Paste")
			(net "SAS_HDD_LED_4")
			(options
				(clearance outline)
				(anchor circle)
			)
			(primitives
				(gr_poly
					(pts
						(arc
							(start -0.1778 0.2794)
							(mid -0.249642 0.249642)
							(end -0.2794 0.1778)
						)
						(arc
							(start -0.2794 -0.1778)
							(mid -0.249642 -0.249642)
							(end -0.1778 -0.2794)
						)
						(arc
							(start 0.1778 -0.2794)
							(mid 0.249642 -0.249642)
							(end 0.2794 -0.1778)
						)
						(arc
							(start 0.2794 0.1778)
							(mid 0.249642 0.249642)
							(end 0.1778 0.2794)
						)
					)
					(width 0)
					(fill yes)
				)
			)
		)
	)
	(footprint ""
		(layer "B.Cu")
		(at 93.136212 -251.587)
		(property "Reference" "TP78"
			(at 0 0 0)
			(layer "B.SilkS")
			(hide yes)
			(effects
				(font
					(size 1.27 1.27)
				)
				(justify mirror)
			)
		)
		(property "Value" "TPAD28"
			(at -0.0127 -1.8034 0)
			(unlocked yes)
			(layer "B.Fab")
			(hide yes)
			(effects
				(font
					(size 1.016 1.016)
					(thickness 0.1524)
				)
				(justify mirror)
			)
		)
		(property "Device Type" "TPAD28"
			(at -0.0127 -3.3274 0)
			(unlocked yes)
			(layer "B.Fab")
			(hide yes)
			(effects
				(font
					(size 1.016 1.016)
					(thickness 0.1524)
				)
				(justify mirror)
			)
		)
		(duplicate_pad_numbers_are_jumpers no)
		(fp_poly
			(pts
				(arc
					(start 0.3556 0)
					(mid -0.3556 0)
					(end 0.3556 0)
				)
			)
			(stroke
				(width 0)
				(type default)
			)
			(fill no)
			(layer "B.CrtYd")
		)
		(fp_poly
			(pts
				(arc
					(start 0.6096 0)
					(mid -0.6096 0)
					(end 0.6096 0)
				)
			)
			(stroke
				(width 0)
				(type default)
			)
			(fill no)
			(layer "B.Fab")
		)
		(pad "1" smd circle
			(at 0 0 180)
			(size 0.7112 0.7112)
			(layers "B.Cu" "B.Mask" "B.Paste")
			(net "SAS_I2C_D_BUF_SCL_R")
		)
	)
)
